FILE_TYPE=LIBRARY_PARTS;
primitive 'CYUSB330468LTXI';
  pin
    'DS1_DP':
      PIN_NUMBER='(60,0)';
      BIDIRECTIONAL='TRUE';
      INPUT_LOAD='(-0.01,0.01)';
      OUTPUT_LOAD='(1.0,-1.0)';
    'DS1_DM':
      PIN_NUMBER='(59,0)';
      BIDIRECTIONAL='TRUE';
      INPUT_LOAD='(-0.01,0.01)';
      OUTPUT_LOAD='(1.0,-1.0)';
    'DS1_RXP':
      PIN_NUMBER='(51,0)';
      INPUT_LOAD='(-0.01,0.01)';
    'DS1_RXM':
      PIN_NUMBER='(50,0)';
      INPUT_LOAD='(-0.01,0.01)';
    'DS1_TXP':
      PIN_NUMBER='(47,0)';
      OUTPUT_LOAD='(1.0,-1.0)';
    'DS1_TXM':
      PIN_NUMBER='(48,0)';
      OUTPUT_LOAD='(1.0,-1.0)';
    'DS2_DP':
      PIN_NUMBER='(62,0)';
      BIDIRECTIONAL='TRUE';
      INPUT_LOAD='(-0.01,0.01)';
      OUTPUT_LOAD='(1.0,-1.0)';
    'DS2_DM':
      PIN_NUMBER='(63,0)';
      BIDIRECTIONAL='TRUE';
      INPUT_LOAD='(-0.01,0.01)';
      OUTPUT_LOAD='(1.0,-1.0)';
    'DS2_RXP':
      PIN_NUMBER='(45,0)';
      INPUT_LOAD='(-0.01,0.01)';
    'DS2_RXM':
      PIN_NUMBER='(44,0)';
      INPUT_LOAD='(-0.01,0.01)';
    'DS2_TXP':
      PIN_NUMBER='(41,0)';
      OUTPUT_LOAD='(1.0,-1.0)';
    'DS2_TXM':
      PIN_NUMBER='(42,0)';
      OUTPUT_LOAD='(1.0,-1.0)';
    'DS3_DP':
      PIN_NUMBER='(65,0)';
      BIDIRECTIONAL='TRUE';
      INPUT_LOAD='(-0.01,0.01)';
      OUTPUT_LOAD='(1.0,-1.0)';
    'DS3_DM':
      PIN_NUMBER='(64,0)';
      BIDIRECTIONAL='TRUE';
      INPUT_LOAD='(-0.01,0.01)';
      OUTPUT_LOAD='(1.0,-1.0)';
    'DS3_RXP':
      PIN_NUMBER='(35,0)';
      INPUT_LOAD='(-0.01,0.01)';
    'DS3_RXM':
      PIN_NUMBER='(36,0)';
      INPUT_LOAD='(-0.01,0.01)';
    'DS3_TXP':
      PIN_NUMBER='(38,0)';
      OUTPUT_LOAD='(1.0,-1.0)';
    'DS3_TXM':
      PIN_NUMBER='(39,0)';
      OUTPUT_LOAD='(1.0,-1.0)';
    'DS4_DP':
      PIN_NUMBER='(67,0)';
      BIDIRECTIONAL='TRUE';
      INPUT_LOAD='(-0.01,0.01)';
      OUTPUT_LOAD='(1.0,-1.0)';
    'DS4_DM':
      PIN_NUMBER='(68,0)';
      BIDIRECTIONAL='TRUE';
      INPUT_LOAD='(-0.01,0.01)';
      OUTPUT_LOAD='(1.0,-1.0)';
    'DS4_RXP':
      PIN_NUMBER='(15,0)';
      INPUT_LOAD='(-0.01,0.01)';
    'DS4_RXM':
      PIN_NUMBER='(14,0)';
      INPUT_LOAD='(-0.01,0.01)';
    'DS4_TXP':
      PIN_NUMBER='(11,0)';
      OUTPUT_LOAD='(1.0,-1.0)';
    'DS4_TXM':
      PIN_NUMBER='(12,0)';
      OUTPUT_LOAD='(1.0,-1.0)';
    'VBUS_DS':
      PIN_NUMBER='(18,0)';
      PINUSE='POWER';
      NO_LOAD_CHECK='Both';
      NO_IO_CHECK='Both';
      NO_ASSERT_CHECK='TRUE';
      NO_DIR_CHECK='TRUE';
      ALLOW_CONNECT='TRUE';
    'I2C_CLK':
      PIN_NUMBER='(32,0)';
      BIDIRECTIONAL='TRUE';
      INPUT_LOAD='(-0.01,0.01)';
      OUTPUT_LOAD='(1.0,-1.0)';
    'I2C_DATA':
      PIN_NUMBER='(33,0)';
      BIDIRECTIONAL='TRUE';
      INPUT_LOAD='(-0.01,0.01)';
      OUTPUT_LOAD='(1.0,-1.0)';
    'SUSPEND':
      PIN_NUMBER='(20,0)';
      BIDIRECTIONAL='TRUE';
      INPUT_LOAD='(-0.01,0.01)';
      OUTPUT_LOAD='(1.0,-1.0)';
    'XTL_IN':
      PIN_NUMBER='(55,0)';
      INPUT_LOAD='(-0.01,0.01)';
    'XTL_OUT':
      PIN_NUMBER='(54,0)';
      OUTPUT_LOAD='(1.0,-1.0)';
    'MODE_SEL0':
      PIN_NUMBER='(23,0)';
      INPUT_LOAD='(-0.01,0.01)';
    'MODE_SEL1':
      PIN_NUMBER='(24,0)';
      INPUT_LOAD='(-0.01,0.01)';
    'GND':
      PIN_NUMBER='(40,0)';
      PINUSE='POWER';
      NO_LOAD_CHECK='Both';
      NO_IO_CHECK='Both';
      NO_ASSERT_CHECK='TRUE';
      NO_DIR_CHECK='TRUE';
      ALLOW_CONNECT='TRUE';
    'VBUS_US':
      PIN_NUMBER='(17,0)';
      PINUSE='POWER';
      NO_LOAD_CHECK='Both';
      NO_IO_CHECK='Both';
      NO_ASSERT_CHECK='TRUE';
      NO_DIR_CHECK='TRUE';
      ALLOW_CONNECT='TRUE';
    'US_DP':
      PIN_NUMBER='(57,0)';
      BIDIRECTIONAL='TRUE';
      INPUT_LOAD='(-0.01,0.01)';
      OUTPUT_LOAD='(1.0,-1.0)';
    'US_DM':
      PIN_NUMBER='(58,0)';
      BIDIRECTIONAL='TRUE';
      INPUT_LOAD='(-0.01,0.01)';
      OUTPUT_LOAD='(1.0,-1.0)';
    'US_RXP':
      PIN_NUMBER='(9,0)';
      INPUT_LOAD='(-0.01,0.01)';
    'US_RXM':
      PIN_NUMBER='(8,0)';
      INPUT_LOAD='(-0.01,0.01)';
    'US_TXP':
      PIN_NUMBER='(6,0)';
      OUTPUT_LOAD='(1.0,-1.0)';
    'US_TXM':
      PIN_NUMBER='(5,0)';
      OUTPUT_LOAD='(1.0,-1.0)';
    'RREF_SS':
      PIN_NUMBER='(26,0)';
      BIDIRECTIONAL='TRUE';
      INPUT_LOAD='(-0.01,0.01)';
      OUTPUT_LOAD='(1.0,-1.0)';
    'RREF_USB2':
      PIN_NUMBER='(2,0)';
      BIDIRECTIONAL='TRUE';
      INPUT_LOAD='(-0.01,0.01)';
      OUTPUT_LOAD='(1.0,-1.0)';
    'NC_25':
      PIN_NUMBER='(25,0)';
      OUTPUT_TYPE='(TS,TS)';
      INPUT_LOAD='(-0.01,0.01)';
      OUTPUT_LOAD='(1.0,-1.0)';
    'PWR_EN':
      PIN_NUMBER='(29,0)';
      BIDIRECTIONAL='TRUE';
      INPUT_LOAD='(-0.01,0.01)';
      OUTPUT_LOAD='(1.0,-1.0)';
    'OVRCURR':
      PIN_NUMBER='(30,0)';
      INPUT_LOAD='(-0.01,0.01)';
    'RESET#':
      PIN_NUMBER='(31,0)';
      INPUT_LOAD='(-0.01,0.01)';
    'RESERVED2':
      PIN_NUMBER='(22,0)';
      BIDIRECTIONAL='TRUE';
      INPUT_LOAD='(-0.01,0.01)';
      OUTPUT_LOAD='(1.0,-1.0)';
    'RESERVED1':
      PIN_NUMBER='(21,0)';
      BIDIRECTIONAL='TRUE';
      INPUT_LOAD='(-0.01,0.01)';
      OUTPUT_LOAD='(1.0,-1.0)';
    'EPAD':
      PIN_NUMBER='(TH,0)';
      PINUSE='POWER';
      NO_LOAD_CHECK='Both';
      NO_IO_CHECK='Both';
      NO_ASSERT_CHECK='TRUE';
      NO_DIR_CHECK='TRUE';
      ALLOW_CONNECT='TRUE';
    'DVDD12_1':
      PIN_NUMBER='(0,1)';
      PINUSE='POWER';
      NO_LOAD_CHECK='Both';
      NO_IO_CHECK='Both';
      NO_ASSERT_CHECK='TRUE';
      NO_DIR_CHECK='TRUE';
      ALLOW_CONNECT='TRUE';
    'DVDD12_2':
      PIN_NUMBER='(0,3)';
      PINUSE='POWER';
      NO_LOAD_CHECK='Both';
      NO_IO_CHECK='Both';
      NO_ASSERT_CHECK='TRUE';
      NO_DIR_CHECK='TRUE';
      ALLOW_CONNECT='TRUE';
    'VDD_EFUSE':
      PIN_NUMBER='(0,19)';
      PINUSE='POWER';
      NO_LOAD_CHECK='Both';
      NO_IO_CHECK='Both';
      NO_ASSERT_CHECK='TRUE';
      NO_DIR_CHECK='TRUE';
      ALLOW_CONNECT='TRUE';
    'DVDD12_3':
      PIN_NUMBER='(0,27)';
      PINUSE='POWER';
      NO_LOAD_CHECK='Both';
      NO_IO_CHECK='Both';
      NO_ASSERT_CHECK='TRUE';
      NO_DIR_CHECK='TRUE';
      ALLOW_CONNECT='TRUE';
    'DVDD12_8':
      PIN_NUMBER='(0,43)';
      PINUSE='POWER';
      NO_LOAD_CHECK='Both';
      NO_IO_CHECK='Both';
      NO_ASSERT_CHECK='TRUE';
      NO_DIR_CHECK='TRUE';
      ALLOW_CONNECT='TRUE';
    'DVDD12_4':
      PIN_NUMBER='(0,49)';
      PINUSE='POWER';
      NO_LOAD_CHECK='Both';
      NO_IO_CHECK='Both';
      NO_ASSERT_CHECK='TRUE';
      NO_DIR_CHECK='TRUE';
      ALLOW_CONNECT='TRUE';
    'AVDD12_6':
      PIN_NUMBER='(0,53)';
      PINUSE='POWER';
      NO_LOAD_CHECK='Both';
      NO_IO_CHECK='Both';
      NO_ASSERT_CHECK='TRUE';
      NO_DIR_CHECK='TRUE';
      ALLOW_CONNECT='TRUE';
    'DVDD12_5':
      PIN_NUMBER='(0,7)';
      PINUSE='POWER';
      NO_LOAD_CHECK='Both';
      NO_IO_CHECK='Both';
      NO_ASSERT_CHECK='TRUE';
      NO_DIR_CHECK='TRUE';
      ALLOW_CONNECT='TRUE';
    'DVDD12_6':
      PIN_NUMBER='(0,13)';
      PINUSE='POWER';
      NO_LOAD_CHECK='Both';
      NO_IO_CHECK='Both';
      NO_ASSERT_CHECK='TRUE';
      NO_DIR_CHECK='TRUE';
      ALLOW_CONNECT='TRUE';
    'DVDD12_7':
      PIN_NUMBER='(0,37)';
      PINUSE='POWER';
      NO_LOAD_CHECK='Both';
      NO_IO_CHECK='Both';
      NO_ASSERT_CHECK='TRUE';
      NO_DIR_CHECK='TRUE';
      ALLOW_CONNECT='TRUE';
    'AVDD33_1':
      PIN_NUMBER='(0,4)';
      PINUSE='POWER';
      NO_LOAD_CHECK='Both';
      NO_IO_CHECK='Both';
      NO_ASSERT_CHECK='TRUE';
      NO_DIR_CHECK='TRUE';
      ALLOW_CONNECT='TRUE';
    'AVDD33_2':
      PIN_NUMBER='(0,56)';
      PINUSE='POWER';
      NO_LOAD_CHECK='Both';
      NO_IO_CHECK='Both';
      NO_ASSERT_CHECK='TRUE';
      NO_DIR_CHECK='TRUE';
      ALLOW_CONNECT='TRUE';
    'AVDD33_3':
      PIN_NUMBER='(0,61)';
      PINUSE='POWER';
      NO_LOAD_CHECK='Both';
      NO_IO_CHECK='Both';
      NO_ASSERT_CHECK='TRUE';
      NO_DIR_CHECK='TRUE';
      ALLOW_CONNECT='TRUE';
    'AVDD33_4':
      PIN_NUMBER='(0,66)';
      PINUSE='POWER';
      NO_LOAD_CHECK='Both';
      NO_IO_CHECK='Both';
      NO_ASSERT_CHECK='TRUE';
      NO_DIR_CHECK='TRUE';
      ALLOW_CONNECT='TRUE';
    'VDD_IO':
      PIN_NUMBER='(0,28)';
      PINUSE='POWER';
      NO_LOAD_CHECK='Both';
      NO_IO_CHECK='Both';
      NO_ASSERT_CHECK='TRUE';
      NO_DIR_CHECK='TRUE';
      ALLOW_CONNECT='TRUE';
    'AVDD12_1':
      PIN_NUMBER='(0,10)';
      PINUSE='POWER';
      NO_LOAD_CHECK='Both';
      NO_IO_CHECK='Both';
      NO_ASSERT_CHECK='TRUE';
      NO_DIR_CHECK='TRUE';
      ALLOW_CONNECT='TRUE';
    'AVDD12_2':
      PIN_NUMBER='(0,16)';
      PINUSE='POWER';
      NO_LOAD_CHECK='Both';
      NO_IO_CHECK='Both';
      NO_ASSERT_CHECK='TRUE';
      NO_DIR_CHECK='TRUE';
      ALLOW_CONNECT='TRUE';
    'AVDD12_3':
      PIN_NUMBER='(0,34)';
      PINUSE='POWER';
      NO_LOAD_CHECK='Both';
      NO_IO_CHECK='Both';
      NO_ASSERT_CHECK='TRUE';
      NO_DIR_CHECK='TRUE';
      ALLOW_CONNECT='TRUE';
    'AVDD12_4':
      PIN_NUMBER='(0,46)';
      PINUSE='POWER';
      NO_LOAD_CHECK='Both';
      NO_IO_CHECK='Both';
      NO_ASSERT_CHECK='TRUE';
      NO_DIR_CHECK='TRUE';
      ALLOW_CONNECT='TRUE';
    'AVDD12_5':
      PIN_NUMBER='(0,52)';
      PINUSE='POWER';
      NO_LOAD_CHECK='Both';
      NO_IO_CHECK='Both';
      NO_ASSERT_CHECK='TRUE';
      NO_DIR_CHECK='TRUE';
      ALLOW_CONNECT='TRUE';
  end_pin;
  body
    PART_NAME='CYUSB330468LTXI';
    BODY_NAME='CYUSB330468LTXI';
    PHYS_DES_PREFIX='U';
    CLASS='IC';
  end_body;
end_primitive;

END.
